FILE_TYPE = CONNECTIVITY;
{Allegro Design Entry HDL 17.2-2016 S081 (4005846) 1/11/2022}
"PAGE_NUMBER" = 155;
0"NC";
1"P3V3_AUX\g";
2"P3V3_AUX\g";
3"P3V3_AUX\g";
4"P3V3_AUX\g";
5"P3V3_AUX\g";
6"GND\g";
7"GND\g";
8"GND\g";
9"GND\g";
10"GND\g";
11"GND\g";
12"GND\g";
13"GND\g";
14"GND\g";
15"GND\g";
16"GND\g";
17"GND\g";
18"GND\g";
19"GND\g";
20"GND\g";
21"GND\g";
22"GND\g";
23"GND\g";
24"GND\g";
25"GND\g";
26"USB_HUB_XTAL_OUT";
27"USB_HUB_XTAL_IN";
28"USB2_HOST_BMC_B_DP";
29"PD_U5201_VREG";
30"PD_U5201_RSTN";
31"USB2_HOST_BMC_B_BUF_DN";
32"USB2_HOST_BMC_B_BUF_DP";
33"RST_USB_HUB_R_N";
34"USB2_HUB_BUF_SWB_DP";
35"USB2_HUB_BUF_SWB_DN";
36"USB2_HUB_BUF_SWB_R_DP";
37"TP_USB2_ENA_HS";
38"TP_USB2_CD";
39"USB2_HUB_BUF_SWB_R_DP";
40"USB2_HUB_BUF_SWB_R_DN";
41"USB2_HOST_BMC_B_DN";
42"USB2_P0_R_DP";
43"USB2_P0_R_DN";
44"USB2_HUB_SWB_DP";
45"USB2_HUB_SWB_DN";
46"NC_USB_HUB_DP2";
47"NC_USB_HUB_DM2";
48"NC_USB_HUB_DP3";
49"NC_USB_HUB_DM4";
50"USB2_HUB_SWB_DN";
51"USB2_HUB_SWB_DP";
52"P3V3_AUX_USB_HUB";
53"USB_HUB_DVDD";
54"USB_HUB_OVCUR1";
55"USB_HUB_OVCUR4";
56"USB_HUB_RREF";
57"USB_HUB_PGANG";
58"NC_USB_HUB_SDA";
59"USB_HUB_PSELF";
60"USB_HUB_OVCUR1";
61"USB_HUB_PSELF";
62"RST_USB_HUB_N";
63"USB_HUB_TEST";
64"NC_USB_HUB_DM3";
65"NC_USB_HUB_DP4";
66"USB2_HUB_BUF_SWB_R_DN";
67"PD_U5201_EQ";
68"USB_HUB_OVCUR3";
69"USB_HUB_OVCUR3";
70"USB_HUB_OVCUR2";
71"USB_HUB_OVCUR2";
72"USB_HUB_OVCUR4";
73"TP_USB2_TEST";
%"GL852GOHY60"
"1","(125,3825)","0","pure_quanta","I100";
;
PART_NUMBER"AL000852001"
ROOM"USB1_BOM1"
VALUE"GL852G-OHY60"
PART_TYPE"SMLF"
MATERIAL"IC"
$LOCATION"U268"
CDS_LIB"pure_quanta"
CDS_LMAN_SYM_OUTLINE"-325,600,325,-600"
NEEDS_NO_SIZE"TRUE"
CDS_LOCATION"U268"
$SEC"1"
CDS_SEC"1";
"DM4"
$PN"15"49;
"DP4"
$PN"16"65;
"DM3"
$PN"12"64;
"DP3"
$PN"13"48;
"DM2"
$PN"6"47;
"DP2"
$PN"7"46;
"DM1"
$PN"3"45;
"DP1"
$PN"4"44;
"DM0"
$PN"1"43;
"DP0"
$PN"2"42;
"RREF"
$PN"8"56;
"PSELF"
$PN"22"61;
"PGANG"
$PN"23"57;
"RESET# \B"
$PN"17"33;
"OVCUR4# \B"
$PN"19"55;
"OVCUR3# \B"
$PN"20"69;
"OVCUR2#||SMD"
$PN"24"70;
"OVCUR1#||SMC"
$PN"25"54;
"TH"
$PN"TH"11;
"DVDD"
$PN"21"53;
"AVDD<2>"
$PN"14"52;
"AVDD<1>"
$PN"9"52;
"AVDD<0>"
$PN"5"52;
"V33"
$PN"28"52;
"V5"
$PN"27"52;
"SDA"
$PN"26"58;
"TEST||SCL"
$PN"18"63;
"X2"
$PN"11"26;
"X1"
$PN"10"27;
%"UNIVERSAL_GND"
"1","(3700,4325)","0","logical_power","I115";
;
HDL_POWER"GND"
CDS_LIB"logical_power";
"A"17;
%"UNIVERSAL_GND"
"1","(4350,4325)","0","logical_power","I116";
;
HDL_POWER"GND"
CDS_LIB"logical_power";
"A"16;
%"UNIVERSAL_GND"
"1","(4475,4150)","0","logical_power","I117";
;
HDL_POWER"GND"
CDS_LIB"logical_power";
"A"15;
%"UNIVERSAL_GND"
"1","(3475,4150)","0","logical_power","I118";
;
HDL_POWER"GND"
CDS_LIB"logical_power";
"A"18;
%"UNIVERSAL_GND"
"1","(2025,4275)","1","logical_power","I122";
;
HDL_POWER"GND"
CDS_LIB"logical_power";
"A"21;
%"Q_RES"
"1","(2550,3875)","0","pure_quanta","I137";
;
PART_NUMBER"CS00002JB13"
ROOM"USB1_BOM1"
PACK_TYPE"0402LF"
MATERIAL"CHIP"
VALUE"0"
$LOCATION"R3652"
CDS_LIB"pure_quanta"
WATTAGE"1/16W"
TOLERANCE"5%"
CDS_LOCATION"R3652"
$SEC"1"
CDS_SEC"1";
"B"
$PN"2"41;
"A"
$PN"1"43;
%"Q_RES"
"1","(2550,3925)","0","pure_quanta","I138";
;
PART_NUMBER"CS00002JB13"
ROOM"USB1_BOM1"
PACK_TYPE"0402LF"
VALUE"0"
MATERIAL"CHIP"
$LOCATION"R3651"
CDS_LIB"pure_quanta"
TOLERANCE"5%"
WATTAGE"1/16W"
CDS_LOCATION"R3651"
$SEC"1"
CDS_SEC"1";
"B"
$PN"2"28;
"A"
$PN"1"42;
%"Q_RES"
"2","(-1075,3100)","0","pure_quanta","I139";
;
PART_NUMBER"CS16802FB03"
PACK_TYPE"0402LF"
MATERIAL"CHIP"
WATTAGE"1/16W"
TOLERANCE"1%"
VALUE"680"
ROOM"USB1_BOM1"
$LOCATION"R3653"
CDS_LIB"pure_quanta"
CDS_LOCATION"R3653"
$SEC"1"
CDS_SEC"1";
"A"
$PN"1"56;
"B"
$PN"2"13;
%"UNIVERSAL_GND"
"1","(-1075,2825)","0","logical_power","I140";
;
HDL_POWER"GND"
CDS_LIB"logical_power";
"A"13;
%"Q_CAP"
"1","(-1175,4500)","2","pure_quanta","I142";
;
PART_NUMBER"CH4104K1B00"
ROOM"USB1_BOM1"
PACK_TYPE"0402"
MATERIAL"X7R"
TOLERANCE"10%"
VOLTAGE"25V"
VALUE"0.1UF"
$LOCATION"C2034"
CDS_LIB"pure_quanta"
CDS_LOCATION"C2034"
$SEC"1"
CDS_SEC"1";
"B"
$PN"2"19;
"A"
$PN"1"52;
%"Q_CAP"
"1","(-1550,4500)","2","pure_quanta","I143";
;
PART_NUMBER"CH4104K1B00"
PACK_TYPE"0402"
MATERIAL"X7R"
TOLERANCE"10%"
VOLTAGE"25V"
VALUE"0.1UF"
ROOM"USB1_BOM1"
$LOCATION"C2033"
CDS_LIB"pure_quanta"
CDS_LOCATION"C2033"
$SEC"1"
CDS_SEC"1";
"B"
$PN"2"19;
"A"
$PN"1"52;
%"UNIVERSAL_POWER"
"1","(-4000,4950)","2","logical_power","I144";
;
HDL_POWER"P3V3_AUX"
CDS_LIB"logical_power";
"A"3;
%"Q_CAP"
"1","(-1925,4500)","2","pure_quanta","I145";
;
PART_NUMBER"CH4104K1B00"
VALUE"0.1UF"
ROOM"USB1_BOM1"
PACK_TYPE"0402"
MATERIAL"X7R"
VOLTAGE"25V"
TOLERANCE"10%"
$LOCATION"C2032"
CDS_LIB"pure_quanta"
CDS_LOCATION"C2032"
$SEC"1"
CDS_SEC"1";
"B"
$PN"2"19;
"A"
$PN"1"52;
%"Q_CAP"
"1","(-825,4500)","0","pure_quanta","I147";
;
PART_NUMBER"CH5104KEB02"
PACK_TYPE"C0402"
MATERIAL"X6S"
TOLERANCE"10%"
VOLTAGE"25V"
VALUE"1UF"
ROOM"USB1_BOM1"
$LOCATION"C2035"
CDS_LIB"pure_quanta"
CDS_LOCATION"C2035"
$SEC"1"
CDS_SEC"1";
"B"
$PN"2"19;
"A"
$PN"1"52;
%"Q_CAP"
"1","(-2300,4500)","0","pure_quanta","I148";
;
PART_NUMBER"CH5104KEB02"
PACK_TYPE"C0402"
MATERIAL"X6S"
TOLERANCE"10%"
VOLTAGE"25V"
VALUE"1UF"
ROOM"USB1_BOM1"
$LOCATION"C2031"
CDS_LIB"pure_quanta"
CDS_LOCATION"C2031"
$SEC"1"
CDS_SEC"1";
"B"
$PN"2"19;
"A"
$PN"1"52;
%"UNIVERSAL_POWER"
"1","(-1900,4075)","2","logical_power","I151";
;
HDL_POWER"P3V3_AUX"
CDS_LIB"logical_power";
"A"4;
%"Q_RES"
"1","(-2725,3425)","0","pure_quanta","I155";
;
PART_NUMBER"CS03322FB03"
ROOM"USB1_BOM1"
PACK_TYPE"0402LF"
WATTAGE"1/16W"
MATERIAL"CHIP"
TOLERANCE"1%"
VALUE"33.2"
$LOCATION"R3654"
CDS_LIB"pure_quanta"
CDS_LOCATION"R3654"
$SEC"1"
CDS_SEC"1";
"B"
$PN"2"33;
"A"
$PN"1"62;
%"UNIVERSAL_GND"
"1","(-2275,2850)","0","logical_power","I157";
;
HDL_POWER"GND"
CDS_LIB"logical_power";
"A"14;
%"Q_CAP"
"1","(-2275,3150)","0","pure_quanta","I158";
;
PART_NUMBER"CH5104KEB02"
ROOM"USB1_BOM1"
VALUE"1UF"
TOLERANCE"10%"
MATERIAL"X6S"
PACK_TYPE"C0402"
VOLTAGE"25V"
$LOCATION"C2041"
CDS_LIB"pure_quanta"
CDS_LOCATION"C2041"
$SEC"1"
CDS_SEC"1";
"B"
$PN"2"14;
"A"
$PN"1"33;
%"Q_RES"
"2","(-1900,3775)","0","pure_quanta","I159";
;
PART_NUMBER"CS31002FB08"
ROOM"USB1_BOM1"
WATTAGE"1/16W"
MATERIAL"CHIP"
TOLERANCE"1%"
VALUE"10K"
PACK_TYPE"0402LF"
$LOCATION"R3660"
CDS_LIB"pure_quanta"
CDS_LOCATION"R3660"
$SEC"1"
CDS_SEC"1";
"A"
$PN"1"4;
"B"
$PN"2"33;
%"Q_RES"
"1","(-3750,4800)","0","pure_quanta","I161";
;
PART_NUMBER"CS00002JB13"
ROOM"USB1_BOM1"
MATERIAL"CHIP"
PACK_TYPE"0402LF"
VALUE"0"
$LOCATION"R3655"
TOLERANCE"5%"
WATTAGE"1/16W"
CDS_LIB"pure_quanta"
CDS_LOCATION"R3655"
$SEC"1"
CDS_SEC"1";
"B"
$PN"2"52;
"A"
$PN"1"3;
%"Q_CAP"
"1","(-2675,4500)","2","pure_quanta","I162";
;
PART_NUMBER"CH4104K1B00"
VALUE"0.1UF"
PACK_TYPE"0402"
MATERIAL"X7R"
TOLERANCE"10%"
VOLTAGE"25V"
ROOM"USB1_BOM1"
$LOCATION"C2040"
CDS_LIB"pure_quanta"
CDS_LOCATION"C2040"
$SEC"1"
CDS_SEC"1";
"B"
$PN"2"19;
"A"
$PN"1"52;
%"Q_CAP"
"1","(-3075,4500)","2","pure_quanta","I163";
;
PART_NUMBER"CH4104K1B00"
VALUE"0.1UF"
TOLERANCE"10%"
ROOM"USB1_BOM1"
PACK_TYPE"0402"
MATERIAL"X7R"
VOLTAGE"25V"
$LOCATION"C2039"
CDS_LIB"pure_quanta"
CDS_LOCATION"C2039"
$SEC"1"
CDS_SEC"1";
"B"
$PN"2"19;
"A"
$PN"1"52;
%"Q_CAP"
"1","(-3450,4500)","0","pure_quanta","I164";
;
PART_NUMBER"CH6101MEB01"
PACK_TYPE"C0402"
MATERIAL"X6S"
TOLERANCE"20%"
VOLTAGE"6.3V"
VALUE"10UF"
ROOM"USB1_BOM1"
$LOCATION"C2038"
CDS_LIB"pure_quanta"
CDS_LOCATION"C2038"
$SEC"1"
CDS_SEC"1";
"B"
$PN"2"19;
"A"
$PN"1"52;
%"UNIVERSAL_GND"
"1","(-3450,4100)","0","logical_power","I165";
;
HDL_POWER"GND"
CDS_LIB"logical_power";
"A"19;
%"UNIVERSAL_GND"
"1","(725,3125)","0","logical_power","I166";
;
HDL_POWER"GND"
CDS_LIB"logical_power";
"A"11;
%"Q_RES"
"1","(-1025,3925)","0","pure_quanta","I167";
;
PART_NUMBER"CS00002JB13"
ROOM"USB1_BOM1"
VALUE"0"
PACK_TYPE"0402LF"
MATERIAL"CHIP"
$LOCATION"R3662"
WATTAGE"1/16W"
TOLERANCE"5%"
CDS_LIB"pure_quanta"
CDS_LOCATION"R3662"
$SEC"1"
CDS_SEC"1";
"B"
$PN"2"53;
"A"
$PN"1"52;
%"Q_RES"
"2","(-750,3075)","0","pure_quanta","I182";
;
PART_NUMBER"CS41002FB09"
VALUE"100K"
TOLERANCE"1%"
WATTAGE"1/16W"
MATERIAL"CHIP"
PACK_TYPE"0402LF"
ROOM"USB1_BOM1"
$LOCATION"R3665"
CDS_LIB"pure_quanta"
CDS_LOCATION"R3665"
$SEC"1"
CDS_SEC"1";
"A"
$PN"1"57;
"B"
$PN"2"12;
%"UNIVERSAL_GND"
"1","(-750,2800)","0","logical_power","I183";
;
HDL_POWER"GND"
CDS_LIB"logical_power";
"A"12;
%"UNIVERSAL_POWER"
"1","(-4150,3400)","2","logical_power","I185";
;
HDL_POWER"P3V3_AUX"
CDS_LIB"logical_power";
"A"2;
%"Q_RES"
"2","(-4150,2950)","0","pure_quanta","I186";
;
PART_NUMBER"CS31002FB08"
ROOM"USB1_BOM1"
MATERIAL"CHIP"
TOLERANCE"1%"
WATTAGE"1/16W"
VALUE"10K"
PACK_TYPE"0402LF"
$LOCATION"R3663"
CDS_LIB"pure_quanta"
CDS_LOCATION"R3663"
$SEC"1"
CDS_SEC"1";
"A"
$PN"1"2;
"B"
$PN"2"59;
%"Q_RES"
"2","(-4150,2350)","0","pure_quanta","I187";
;
PART_NUMBER"CS31002FB08"
MATERIAL"EMPTY"
WATTAGE"1/16W"
VALUE"10K"
TOLERANCE"1%"
PACK_TYPE"0402LF"
$LOCATION"R3664"
CDS_LIB"pure_quanta"
CDS_LOCATION"R3664"
$SEC"1"
CDS_SEC"1";
"A"
$PN"1"59;
"B"
$PN"2"20;
%"UNIVERSAL_GND"
"1","(-4150,1925)","0","logical_power","I188";
;
HDL_POWER"GND"
CDS_LIB"logical_power";
"A"20;
%"Q_RES"
"1","(-1550,2275)","0","pure_quanta","I194";
;
PART_NUMBER"CS31002FB08"
MATERIAL"EMPTY"
VALUE"10K"
$LOCATION"R3656"
CDS_LIB"pure_quanta"
PACK_TYPE"0402LF"
TOLERANCE"1%"
WATTAGE"1/16W"
CDS_LOCATION"R3656"
$SEC"1"
CDS_SEC"1";
"B"
$PN"2"60;
"A"
$PN"1"5;
%"Q_RES"
"1","(-1550,2125)","0","pure_quanta","I195";
;
PART_NUMBER"CS31002FB08"
VALUE"10K"
MATERIAL"EMPTY"
$LOCATION"R3657"
CDS_LIB"pure_quanta"
WATTAGE"1/16W"
TOLERANCE"1%"
PACK_TYPE"0402LF"
CDS_LOCATION"R3657"
$SEC"1"
CDS_SEC"1";
"B"
$PN"2"71;
"A"
$PN"1"5;
%"Q_RES"
"1","(-1550,2000)","0","pure_quanta","I196";
;
PART_NUMBER"CS31002FB08"
VALUE"10K"
MATERIAL"EMPTY"
$LOCATION"R3658"
WATTAGE"1/16W"
TOLERANCE"1%"
PACK_TYPE"0402LF"
CDS_LIB"pure_quanta"
CDS_LOCATION"R3658"
$SEC"1"
CDS_SEC"1";
"B"
$PN"2"68;
"A"
$PN"1"5;
%"UNIVERSAL_POWER"
"1","(-2175,2525)","2","logical_power","I197";
;
HDL_POWER"P3V3_AUX"
CDS_LIB"logical_power";
"A"5;
%"Q_RES"
"1","(-1550,1875)","0","pure_quanta","I198";
;
PART_NUMBER"CS31002FB08"
MATERIAL"EMPTY"
TOLERANCE"1%"
PACK_TYPE"0402LF"
VALUE"10K"
WATTAGE"1/16W"
$LOCATION"R3659"
CDS_LIB"pure_quanta"
CDS_LOCATION"R3659"
$SEC"1"
CDS_SEC"1";
"B"
$PN"2"72;
"A"
$PN"1"5;
%"Q_RES"
"1","(1375,4275)","0","pure_quanta","I199";
;
PART_NUMBER"CS00002JB13"
ROOM"USB1_BOM1"
MATERIAL"CHIP"
PACK_TYPE"0402LF"
VALUE"0"
$LOCATION"R3666"
WATTAGE"1/16W"
TOLERANCE"5%"
CDS_LIB"pure_quanta"
CDS_LOCATION"R3666"
$SEC"1"
CDS_SEC"1";
"B"
$PN"2"21;
"A"
$PN"1"63;
%"Q_XTAL_4P_13BI_24GND"
"1","(4025,4550)","0","pure_quanta","I200";
;
PART_NUMBER"BG6120000E0"
VALUE"12MHZ"
PART_TYPE"SMLF"
MATERIAL"MISC"
ROOM"USB1_BOM1"
LOCATION"Y4"
CDS_LMAN_SYM_OUTLINE"-125,175,125,-175"
PIN_NAMES_ROTATE"True"
CDS_LIB"pure_quanta"
$SEC"1"
CDS_SEC"1";
"X2"
$PN"3"26;
"G2"
$PN"4"16;
"G1"
$PN"2"17;
"X1"
$PN"1"27;
%"Q_RES"
"1","(-1900,3100)","1","pure_quanta","I201";
;
PART_NUMBER"CS34702BB05"
VALUE"47K"
PACK_TYPE"0402LF"
MATERIAL"EMPTY"
WATTAGE"1/16W"
TOLERANCE"0.1%"
LOCATION"R3661"
CDS_LIB"pure_quanta"
$SEC"1"
CDS_SEC"1";
"B"
$PN"2"33;
"A"
$PN"1"14;
%"Q_RES"
"2","(3625,3675)","0","pure_quanta","I202";
;
PART_NUMBER"CS04992FB07"
VALUE"49.9"
MATERIAL"EMPTY"
$LOCATION"R4420"
PACK_TYPE"0402LF"
TOLERANCE"1%"
WATTAGE"1/16W"
CDS_LIB"pure_quanta"
CDS_LOCATION"R4420"
$SEC"1"
CDS_SEC"1";
"A"
$PN"1"41;
"B"
$PN"2"22;
%"Q_RES"
"2","(3450,3675)","0","pure_quanta","I203";
;
PART_NUMBER"CS04992FB07"
VALUE"49.9"
MATERIAL"EMPTY"
$LOCATION"R4419"
WATTAGE"1/16W"
TOLERANCE"1%"
PACK_TYPE"0402LF"
CDS_LIB"pure_quanta"
CDS_LOCATION"R4419"
$SEC"1"
CDS_SEC"1";
"A"
$PN"1"28;
"B"
$PN"2"23;
%"UNIVERSAL_GND"
"1","(3625,3450)","0","logical_power","I204";
;
CDS_LIB"logical_power"
HDL_POWER"GND";
"A"22;
%"UNIVERSAL_GND"
"1","(3450,3450)","0","logical_power","I205";
;
CDS_LIB"logical_power"
HDL_POWER"GND";
"A"23;
%"Q_RES"
"2","(-2275,1025)","0","pure_quanta","I206";
;
PART_NUMBER"CS04992FB07"
VALUE"49.9"
MATERIAL"EMPTY"
$LOCATION"R4483"
PACK_TYPE"0402LF"
TOLERANCE"1%"
WATTAGE"1/16W"
CDS_LIB"pure_quanta"
CDS_LOCATION"R4483"
$SEC"1"
CDS_SEC"1";
"A"
$PN"1"31;
"B"
$PN"2"24;
%"UNIVERSAL_GND"
"1","(-2275,800)","0","logical_power","I207";
;
CDS_LIB"logical_power"
HDL_POWER"GND";
"A"24;
%"Q_RES"
"2","(-2450,1025)","0","pure_quanta","I208";
;
PART_NUMBER"CS04992FB07"
VALUE"49.9"
MATERIAL"EMPTY"
$LOCATION"R4482"
WATTAGE"1/16W"
TOLERANCE"1%"
PACK_TYPE"0402LF"
CDS_LIB"pure_quanta"
CDS_LOCATION"R4482"
$SEC"1"
CDS_SEC"1";
"A"
$PN"1"32;
"B"
$PN"2"25;
%"UNIVERSAL_GND"
"1","(-2450,800)","0","logical_power","I209";
;
CDS_LIB"logical_power"
HDL_POWER"GND";
"A"25;
%"Q_CAP"
"1","(3475,4375)","0","pure_quanta","I210";
;
PART_NUMBER"CH01806JB07"
TOLERANCE"5%"
PACK_TYPE"0402"
MATERIAL"C0G"
VOLTAGE"50V"
VALUE"18PF"
ROOM"USB1_BOM1"
LOCATION"C2029"
CDS_LIB"pure_quanta"
$SEC"1"
CDS_SEC"1";
"B"
$PN"2"18;
"A"
$PN"1"27;
%"Q_CAP"
"1","(4475,4375)","0","pure_quanta","I211";
;
PART_NUMBER"CH01806JB07"
MATERIAL"C0G"
PACK_TYPE"0402"
VOLTAGE"50V"
ROOM"USB1_BOM1"
VALUE"18PF"
TOLERANCE"5%"
LOCATION"C2030"
CDS_LIB"pure_quanta"
$SEC"1"
CDS_SEC"1";
"B"
$PN"2"15;
"A"
$PN"1"26;
%"Q_RES"
"1","(-2175,175)","0","pure_quanta","I78";
;
PART_NUMBER"CS00002JB13"
VALUE"0"
ROOM"USB1_BOM1"
PACK_TYPE"0402LF"
MATERIAL"CHIP"
$LOCATION"R2787"
CDS_LIB"pure_quanta"
WATTAGE"1/16W"
TOLERANCE"5%"
CDS_LOCATION"R2787"
$SEC"1"
CDS_SEC"1";
"B"
$PN"2"40;
"A"
$PN"1"50;
%"Q_RES"
"1","(-2175,225)","0","pure_quanta","I79";
;
PART_NUMBER"CS00002JB13"
ROOM"USB1_BOM1"
PACK_TYPE"0402LF"
VALUE"0"
MATERIAL"CHIP"
$LOCATION"R2786"
CDS_LIB"pure_quanta"
WATTAGE"1/16W"
TOLERANCE"5%"
CDS_LOCATION"R2786"
$SEC"1"
CDS_SEC"1";
"B"
$PN"2"36;
"A"
$PN"1"51;
%"UNIVERSAL_GND"
"1","(-1150,-450)","0","logical_power","I80";
;
HDL_POWER"GND"
CDS_LIB"logical_power";
"A"10;
%"Q_CAP"
"1","(-1150,-225)","0","pure_quanta","I81";
;
PART_NUMBER"CH4104K1B00"
MATERIAL"EMPTY"
TOLERANCE"10%"
VOLTAGE"25V"
ROOM"USB1_BOM2"
VALUE"0.1UF"
PACK_TYPE"0402"
$LOCATION"C5232"
CDS_LIB"pure_quanta"
CDS_LOCATION"C5232"
$SEC"1"
CDS_SEC"1";
"B"
$PN"2"10;
"A"
$PN"1"30;
%"UNIVERSAL_GND"
"1","(-675,-450)","0","logical_power","I82";
;
HDL_POWER"GND"
CDS_LIB"logical_power";
"A"9;
%"Q_RES"
"2","(-675,-250)","0","pure_quanta","I83";
;
PART_NUMBER"CS23902JB04"
MATERIAL"EMPTY"
VALUE"3.9K"
WATTAGE"1/16W"
TOLERANCE"5%"
PACK_TYPE"0402LF"
ROOM"USB1_BOM2"
$LOCATION"R5238"
CDS_LIB"pure_quanta"
CDS_LOCATION"R5238"
$SEC"1"
CDS_SEC"1";
"A"
$PN"1"67;
"B"
$PN"2"9;
%"TUSB211IRWBR"
"1","(-125,100)","0","pure_quanta","I84";
;
PART_NUMBER"AL000211007"
PART_TYPE"SMLF"
VALUE"TUSB211IRWBR"
ROOM"USB1_BOM2"
MATERIAL"EMPTY"
$LOCATION"U5201"
CDS_LIB"pure_quanta"
CDS_LMAN_SYM_OUTLINE"-225,175,225,-175"
NEEDS_NO_SIZE"TRUE"
CDS_LOCATION"U5201"
$SEC"1"
CDS_SEC"1";
"GND"
$PN"10"7;
"EQ"
$PN"6"67;
"D2P"
$PN"7"39;
"D1P"
$PN"2"36;
"D1M"
$PN"1"40;
"CD"
$PN"4"38;
"ENA_HS"
$PN"9"37;
"VCC"
$PN"12"1;
"TEST"
$PN"3"73;
"VREG"
$PN"11"29;
"D2M"
$PN"8"66;
"RSTN"
$PN"5"30;
%"UNIVERSAL_GND"
"1","(1475,-425)","0","logical_power","I85";
;
HDL_POWER"GND"
CDS_LIB"logical_power";
"A"8;
%"UNIVERSAL_GND"
"1","(1375,-150)","0","logical_power","I86";
;
HDL_POWER"GND"
CDS_LIB"logical_power";
"A"7;
%"Q_CAP"
"1","(1475,-200)","0","pure_quanta","I87";
;
PART_NUMBER"CH4104K1B00"
MATERIAL"EMPTY"
TOLERANCE"10%"
VOLTAGE"25V"
VALUE"0.1UF"
ROOM"USB1_BOM2"
PACK_TYPE"0402"
$LOCATION"C5236"
CDS_LIB"pure_quanta"
CDS_LOCATION"C5236"
$SEC"1"
CDS_SEC"1";
"B"
$PN"2"8;
"A"
$PN"1"29;
%"Q_CAP"
"1","(75,750)","0","pure_quanta","I88";
;
PART_NUMBER"CH5104KEB02"
VALUE"1UF"
VOLTAGE"25V"
PACK_TYPE"C0402"
ROOM"USB1_BOM2"
TOLERANCE"10%"
MATERIAL"EMPTY"
$LOCATION"C5229"
CDS_LIB"pure_quanta"
CDS_LOCATION"C5229"
$SEC"1"
CDS_SEC"1";
"B"
$PN"2"6;
"A"
$PN"1"1;
%"UNIVERSAL_GND"
"1","(575,375)","0","logical_power","I89";
;
HDL_POWER"GND"
CDS_LIB"logical_power";
"A"6;
%"Q_RES"
"1","(1375,175)","0","pure_quanta","I90";
;
PART_NUMBER"CS00002JB13"
PACK_TYPE"0402LF"
VALUE"0"
MATERIAL"CHIP"
$LOCATION"R5236"
CDS_LIB"pure_quanta"
TOLERANCE"5%"
WATTAGE"1/16W"
CDS_LOCATION"R5236"
$SEC"1"
CDS_SEC"1";
"B"
$PN"2"35;
"A"
$PN"1"66;
%"Q_RES"
"1","(1375,225)","0","pure_quanta","I91";
;
PART_NUMBER"CS00002JB13"
PACK_TYPE"0402LF"
MATERIAL"CHIP"
VALUE"0"
$LOCATION"R5234"
CDS_LIB"pure_quanta"
TOLERANCE"5%"
WATTAGE"1/16W"
CDS_LOCATION"R5234"
$SEC"1"
CDS_SEC"1";
"B"
$PN"2"34;
"A"
$PN"1"39;
%"Q_CAP"
"1","(575,725)","0","pure_quanta","I92";
;
PART_NUMBER"CH4104K1B00"
MATERIAL"EMPTY"
ROOM"USB1_BOM2"
VALUE"0.1UF"
VOLTAGE"25V"
TOLERANCE"10%"
PACK_TYPE"0402"
$LOCATION"C5234"
CDS_LIB"pure_quanta"
CDS_LOCATION"C5234"
$SEC"1"
CDS_SEC"1";
"B"
$PN"2"6;
"A"
$PN"1"1;
%"UNIVERSAL_POWER"
"1","(1125,1050)","2","logical_power","I95";
;
HDL_POWER"P3V3_AUX"
CDS_LIB"logical_power";
"A"1;
%"Q_RES"
"2","(2725,3650)","0","pure_quanta","I96";
;
PART_NUMBER"CS00002JB13"
VALUE"0"
MATERIAL"EMPTY"
ROOM"USB1_BOM2"
$LOCATION"R2790"
CDS_LIB"pure_quanta"
PACK_TYPE"0402LF"
TOLERANCE"5%"
WATTAGE"1/16W"
CDS_LOCATION"R2790"
$SEC"1"
CDS_SEC"1";
"A"
$PN"1"28;
"B"
$PN"2"32;
%"Q_RES"
"2","(2825,3650)","0","pure_quanta","I97";
;
PART_NUMBER"CS00002JB13"
MATERIAL"EMPTY"
PACK_TYPE"0402LF"
WATTAGE"1/16W"
TOLERANCE"5%"
VALUE"0"
ROOM"USB1_BOM2"
$LOCATION"R2791"
CDS_LIB"pure_quanta"
CDS_LOCATION"R2791"
$SEC"1"
CDS_SEC"1";
"A"
$PN"1"41;
"B"
$PN"2"31;
%"Q_RES"
"2","(-1950,375)","0","pure_quanta","I98";
;
PART_NUMBER"CS00002JB13"
VALUE"0"
MATERIAL"EMPTY"
ROOM"USB1_BOM2"
$LOCATION"R2789"
CDS_LIB"pure_quanta"
PACK_TYPE"0402LF"
TOLERANCE"5%"
WATTAGE"1/16W"
CDS_LOCATION"R2789"
$SEC"1"
CDS_SEC"1";
"A"
$PN"1"31;
"B"
$PN"2"40;
%"Q_RES"
"2","(-2025,375)","0","pure_quanta","I99";
;
PART_NUMBER"CS00002JB13"
PACK_TYPE"0402LF"
VALUE"0"
WATTAGE"1/16W"
TOLERANCE"5%"
MATERIAL"EMPTY"
ROOM"USB1_BOM2"
$LOCATION"R2788"
CDS_LIB"pure_quanta"
CDS_LOCATION"R2788"
$SEC"1"
CDS_SEC"1";
"A"
$PN"1"32;
"B"
$PN"2"36;
END.
